(kicad_pcb
	(version 20260206)
	(generator "pcbnew")
	(generator_version "10.0")
	(general
		(thickness 1.6)
		(legacy_teardrops no)
	)
	(paper "A4")
	(title_block
		(title "Bryce Canyon_SCC_16316-1_OCP.brd")
		(comment 1 "Bryce Canyon / footprints 1559-1561 of 1561")
	)
	(layers
		(0 "F.Cu" signal "TOP")
		(4 "In1.Cu" signal "L2GND")
		(6 "In2.Cu" signal "L3")
		(8 "In3.Cu" signal "L4VCC")
		(10 "In4.Cu" signal "L5VCC")
		(12 "In5.Cu" signal "L6")
		(14 "In6.Cu" signal "L7GND")
		(2 "B.Cu" signal "BOTTOM")
		(9 "F.Adhes" user "F.Adhesive")
		(11 "B.Adhes" user "B.Adhesive")
		(13 "F.Paste" user "Package Geometry/Pastemask Top")
		(15 "B.Paste" user "Package Geometry/Pastemask Bottom")
		(5 "F.SilkS" user "Ref Des/Silkscreen Top")
		(7 "B.SilkS" user "Ref Des/Silkscreen Bottom")
		(1 "F.Mask" user "Board Geometry/Soldermask Top")
		(3 "B.Mask" user "Board Geometry/Soldermask Bottom")
		(17 "Dwgs.User" user "User.Drawings")
		(19 "Cmts.User" user "User.Comments")
		(21 "Eco1.User" user "User.Eco1")
		(23 "Eco2.User" user "User.Eco2")
		(25 "Edge.Cuts" user "Board Geometry/Outline")
		(27 "Margin" user)
		(31 "F.CrtYd" user "Package Geometry/Place Bound Top")
		(29 "B.CrtYd" user "Package Geometry/Place Bound Bottom")
		(35 "F.Fab" user "Ref Des/Assembly Top")
		(33 "B.Fab" user "Ref Des/Assembly Bottom")
	)
	(footprint ""
		(layer "B.Cu")
		(at 111.94796 -87.107776 180)
		(property "Reference" "R138"
			(at 0 0 0)
			(layer "B.SilkS")
			(hide yes)
			(effects
				(font
					(size 1.27 1.27)
				)
				(justify mirror)
			)
		)
		(property "Value" "4K75R2F-1-GP"
			(at -0.064008 -3.993896 180)
			(unlocked yes)
			(layer "B.Fab")
			(hide yes)
			(effects
				(font
					(size 1.016 1.016)
					(thickness 0.1524)
				)
				(justify mirror)
			)
		)
		(property "Device Type" "R402H16"
			(at -0.064008 -5.517896 180)
			(unlocked yes)
			(layer "B.Fab")
			(hide yes)
			(effects
				(font
					(size 1.016 1.016)
					(thickness 0.1524)
				)
				(justify mirror)
			)
		)
		(duplicate_pad_numbers_are_jumpers no)
		(fp_line
			(start 0.508 -0.9398)
			(end 0.508 0.9398)
			(stroke
				(width 0.1524)
				(type default)
			)
			(layer "B.SilkS")
		)
		(fp_line
			(start -0.508 -0.9398)
			(end 0.508 -0.9398)
			(stroke
				(width 0.1524)
				(type default)
			)
			(layer "B.SilkS")
		)
		(fp_rect
			(start 0.508 0.9398)
			(end -0.508 -0.9398)
			(stroke
				(width 0)
				(type default)
			)
			(fill no)
			(layer "B.CrtYd")
		)
		(fp_rect
			(start 0.508 0.9398)
			(end -0.508 -0.9398)
			(stroke
				(width 0)
				(type default)
			)
			(fill no)
			(layer "B.Fab")
		)
		(pad "1" smd custom
			(at 0 -0.4445)
			(size 0.1397 0.1397)
			(layers "B.Cu" "B.Mask" "B.Paste")
			(net "EXP_XM_NOR_CS_N")
			(options
				(clearance outline)
				(anchor circle)
			)
			(primitives
				(gr_poly
					(pts
						(arc
							(start -0.1778 0.2794)
							(mid -0.249642 0.249642)
							(end -0.2794 0.1778)
						)
						(arc
							(start -0.2794 -0.1778)
							(mid -0.249642 -0.249642)
							(end -0.1778 -0.2794)
						)
						(arc
							(start 0.1778 -0.2794)
							(mid 0.249642 -0.249642)
							(end 0.2794 -0.1778)
						)
						(arc
							(start 0.2794 0.1778)
							(mid 0.249642 0.249642)
							(end 0.1778 0.2794)
						)
					)
					(width 0)
					(fill yes)
				)
			)
		)
		(pad "2" smd custom
			(at 0 0.4445)
			(size 0.1397 0.1397)
			(layers "B.Cu" "B.Mask" "B.Paste")
			(net "P1V8_E")
			(options
				(clearance outline)
				(anchor circle)
			)
			(primitives
				(gr_poly
					(pts
						(arc
							(start -0.1778 0.2794)
							(mid -0.249642 0.249642)
							(end -0.2794 0.1778)
						)
						(arc
							(start -0.2794 -0.1778)
							(mid -0.249642 -0.249642)
							(end -0.1778 -0.2794)
						)
						(arc
							(start 0.1778 -0.2794)
							(mid 0.249642 -0.249642)
							(end 0.2794 -0.1778)
						)
						(arc
							(start 0.2794 0.1778)
							(mid 0.249642 0.249642)
							(end 0.1778 0.2794)
						)
					)
					(width 0)
					(fill yes)
				)
			)
		)
	)
	(footprint ""
		(layer "B.Cu")
		(at 90.986356 -78.323948 180)
		(property "Reference" "R155"
			(at 0 0 0)
			(layer "B.SilkS")
			(hide yes)
			(effects
				(font
					(size 1.27 1.27)
				)
				(justify mirror)
			)
		)
		(property "Value" "10R2F-L-GP"
			(at -0.064008 -3.993896 180)
			(unlocked yes)
			(layer "B.Fab")
			(hide yes)
			(effects
				(font
					(size 1.016 1.016)
					(thickness 0.1524)
				)
				(justify mirror)
			)
		)
		(property "Device Type" "R402H14"
			(at -0.064008 -5.517896 180)
			(unlocked yes)
			(layer "B.Fab")
			(hide yes)
			(effects
				(font
					(size 1.016 1.016)
					(thickness 0.1524)
				)
				(justify mirror)
			)
		)
		(duplicate_pad_numbers_are_jumpers no)
		(fp_line
			(start 0.508 -0.9398)
			(end 0.508 0.9398)
			(stroke
				(width 0.1524)
				(type default)
			)
			(layer "B.SilkS")
		)
		(fp_line
			(start -0.508 -0.9398)
			(end 0.508 -0.9398)
			(stroke
				(width 0.1524)
				(type default)
			)
			(layer "B.SilkS")
		)
		(fp_rect
			(start 0.508 0.9398)
			(end -0.508 -0.9398)
			(stroke
				(width 0)
				(type default)
			)
			(fill no)
			(layer "B.CrtYd")
		)
		(fp_rect
			(start 0.508 0.9398)
			(end -0.508 -0.9398)
			(stroke
				(width 0)
				(type default)
			)
			(fill no)
			(layer "B.Fab")
		)
		(pad "1" smd custom
			(at 0 -0.4445)
			(size 0.1397 0.1397)
			(layers "B.Cu" "B.Mask" "B.Paste")
			(net "P0V9")
			(options
				(clearance outline)
				(anchor circle)
			)
			(primitives
				(gr_poly
					(pts
						(arc
							(start -0.1778 0.2794)
							(mid -0.249642 0.249642)
							(end -0.2794 0.1778)
						)
						(arc
							(start -0.2794 -0.1778)
							(mid -0.249642 -0.249642)
							(end -0.1778 -0.2794)
						)
						(arc
							(start 0.1778 -0.2794)
							(mid 0.249642 -0.249642)
							(end 0.2794 -0.1778)
						)
						(arc
							(start 0.2794 0.1778)
							(mid 0.249642 0.249642)
							(end 0.1778 0.2794)
						)
					)
					(width 0)
					(fill yes)
				)
			)
		)
		(pad "2" smd custom
			(at 0 0.4445)
			(size 0.1397 0.1397)
			(layers "B.Cu" "B.Mask" "B.Paste")
			(net "SYSPLL_VDDA09")
			(options
				(clearance outline)
				(anchor circle)
			)
			(primitives
				(gr_poly
					(pts
						(arc
							(start -0.1778 0.2794)
							(mid -0.249642 0.249642)
							(end -0.2794 0.1778)
						)
						(arc
							(start -0.2794 -0.1778)
							(mid -0.249642 -0.249642)
							(end -0.1778 -0.2794)
						)
						(arc
							(start 0.1778 -0.2794)
							(mid 0.249642 -0.249642)
							(end 0.2794 -0.1778)
						)
						(arc
							(start 0.2794 0.1778)
							(mid 0.249642 0.249642)
							(end 0.1778 0.2794)
						)
					)
					(width 0)
					(fill yes)
				)
			)
		)
	)
	(footprint ""
		(layer "B.Cu")
		(at 179.68214 -43.139868 90)
		(property "Reference" "C449"
			(at 0 0 90)
			(layer "B.SilkS")
			(hide yes)
			(effects
				(font
					(size 1.27 1.27)
				)
				(justify mirror)
			)
		)
		(property "Value" "SC1KP50V2KX-1GP"
			(at -1.1811 -2.7051 90)
			(unlocked yes)
			(layer "B.Fab")
			(hide yes)
			(effects
				(font
					(size 1.016 1.016)
					(thickness 0.1524)
				)
				(justify mirror)
			)
		)
		(property "Device Type" "C402H22"
			(at -1.1811 -4.2291 90)
			(unlocked yes)
			(layer "B.Fab")
			(hide yes)
			(effects
				(font
					(size 1.016 1.016)
					(thickness 0.1524)
				)
				(justify mirror)
			)
		)
		(duplicate_pad_numbers_are_jumpers no)
		(fp_rect
			(start 0.4318 0.9525)
			(end -0.4318 -0.9525)
			(stroke
				(width 0)
				(type default)
			)
			(fill no)
			(layer "B.CrtYd")
		)
		(fp_rect
			(start 0.4318 0.9525)
			(end -0.4318 -0.9525)
			(stroke
				(width 0)
				(type default)
			)
			(fill no)
			(layer "B.Fab")
		)
		(pad "1" smd custom
			(at 0 -0.4445 270)
			(size 0.1524 0.1524)
			(layers "B.Cu" "B.Mask" "B.Paste")
			(net "P0V975")
			(options
				(clearance outline)
				(anchor circle)
			)
			(primitives
				(gr_poly
					(pts
						(arc
							(start 0.3048 0.2032)
							(mid 0.275042 0.275042)
							(end 0.2032 0.3048)
						)
						(arc
							(start -0.2032 0.3048)
							(mid -0.275042 0.275042)
							(end -0.3048 0.2032)
						)
						(arc
							(start -0.3048 -0.2032)
							(mid -0.275042 -0.275042)
							(end -0.2032 -0.3048)
						)
						(arc
							(start 0.2032 -0.3048)
							(mid 0.275042 -0.275042)
							(end 0.3048 -0.2032)
						)
					)
					(width 0)
					(fill yes)
				)
			)
		)
		(pad "2" smd custom
			(at 0 0.4445 270)
			(size 0.1524 0.1524)
			(layers "B.Cu" "B.Mask" "B.Paste")
			(net "GND")
			(options
				(clearance outline)
				(anchor circle)
			)
			(primitives
				(gr_poly
					(pts
						(arc
							(start 0.3048 0.2032)
							(mid 0.275042 0.275042)
							(end 0.2032 0.3048)
						)
						(arc
							(start -0.2032 0.3048)
							(mid -0.275042 0.275042)
							(end -0.3048 0.2032)
						)
						(arc
							(start -0.3048 -0.2032)
							(mid -0.275042 -0.275042)
							(end -0.2032 -0.3048)
						)
						(arc
							(start 0.2032 -0.3048)
							(mid 0.275042 -0.275042)
							(end 0.3048 -0.2032)
						)
					)
					(width 0)
					(fill yes)
				)
			)
		)
	)
)
